FILE_TYPE=LIBRARY_PARTS;
primitive 'CONN112_10137002101LF';
  pin
    'A8':
      PIN_NUMBER='(A8,0)';
      BIDIRECTIONAL='TRUE';
      INPUT_LOAD='(-0.01,0.01)';
      OUTPUT_LOAD='(1.0,-1.0)';
    'A7':
      PIN_NUMBER='(A7,0)';
      BIDIRECTIONAL='TRUE';
      INPUT_LOAD='(-0.01,0.01)';
      OUTPUT_LOAD='(1.0,-1.0)';
    'A6':
      PIN_NUMBER='(A6,0)';
      BIDIRECTIONAL='TRUE';
      INPUT_LOAD='(-0.01,0.01)';
      OUTPUT_LOAD='(1.0,-1.0)';
    'A5':
      PIN_NUMBER='(A5,0)';
      BIDIRECTIONAL='TRUE';
      INPUT_LOAD='(-0.01,0.01)';
      OUTPUT_LOAD='(1.0,-1.0)';
    'B8':
      PIN_NUMBER='(B8,0)';
      BIDIRECTIONAL='TRUE';
      INPUT_LOAD='(-0.01,0.01)';
      OUTPUT_LOAD='(1.0,-1.0)';
    'B7':
      PIN_NUMBER='(B7,0)';
      BIDIRECTIONAL='TRUE';
      INPUT_LOAD='(-0.01,0.01)';
      OUTPUT_LOAD='(1.0,-1.0)';
    'B6':
      PIN_NUMBER='(B6,0)';
      BIDIRECTIONAL='TRUE';
      INPUT_LOAD='(-0.01,0.01)';
      OUTPUT_LOAD='(1.0,-1.0)';
    'B5':
      PIN_NUMBER='(B5,0)';
      BIDIRECTIONAL='TRUE';
      INPUT_LOAD='(-0.01,0.01)';
      OUTPUT_LOAD='(1.0,-1.0)';
    'C8':
      PIN_NUMBER='(C8,0)';
      BIDIRECTIONAL='TRUE';
      INPUT_LOAD='(-0.01,0.01)';
      OUTPUT_LOAD='(1.0,-1.0)';
    'C7':
      PIN_NUMBER='(C7,0)';
      BIDIRECTIONAL='TRUE';
      INPUT_LOAD='(-0.01,0.01)';
      OUTPUT_LOAD='(1.0,-1.0)';
    'C6':
      PIN_NUMBER='(C6,0)';
      BIDIRECTIONAL='TRUE';
      INPUT_LOAD='(-0.01,0.01)';
      OUTPUT_LOAD='(1.0,-1.0)';
    'C5':
      PIN_NUMBER='(C5,0)';
      BIDIRECTIONAL='TRUE';
      INPUT_LOAD='(-0.01,0.01)';
      OUTPUT_LOAD='(1.0,-1.0)';
    'D8':
      PIN_NUMBER='(D8,0)';
      BIDIRECTIONAL='TRUE';
      INPUT_LOAD='(-0.01,0.01)';
      OUTPUT_LOAD='(1.0,-1.0)';
    'D7':
      PIN_NUMBER='(D7,0)';
      BIDIRECTIONAL='TRUE';
      INPUT_LOAD='(-0.01,0.01)';
      OUTPUT_LOAD='(1.0,-1.0)';
    'D6':
      PIN_NUMBER='(D6,0)';
      BIDIRECTIONAL='TRUE';
      INPUT_LOAD='(-0.01,0.01)';
      OUTPUT_LOAD='(1.0,-1.0)';
    'D5':
      PIN_NUMBER='(D5,0)';
      BIDIRECTIONAL='TRUE';
      INPUT_LOAD='(-0.01,0.01)';
      OUTPUT_LOAD='(1.0,-1.0)';
    'E8':
      PIN_NUMBER='(E8,0)';
      BIDIRECTIONAL='TRUE';
      INPUT_LOAD='(-0.01,0.01)';
      OUTPUT_LOAD='(1.0,-1.0)';
    'E7':
      PIN_NUMBER='(E7,0)';
      BIDIRECTIONAL='TRUE';
      INPUT_LOAD='(-0.01,0.01)';
      OUTPUT_LOAD='(1.0,-1.0)';
    'E6':
      PIN_NUMBER='(E6,0)';
      BIDIRECTIONAL='TRUE';
      INPUT_LOAD='(-0.01,0.01)';
      OUTPUT_LOAD='(1.0,-1.0)';
    'E5':
      PIN_NUMBER='(E5,0)';
      BIDIRECTIONAL='TRUE';
      INPUT_LOAD='(-0.01,0.01)';
      OUTPUT_LOAD='(1.0,-1.0)';
    'F8':
      PIN_NUMBER='(F8,0)';
      BIDIRECTIONAL='TRUE';
      INPUT_LOAD='(-0.01,0.01)';
      OUTPUT_LOAD='(1.0,-1.0)';
    'F7':
      PIN_NUMBER='(F7,0)';
      BIDIRECTIONAL='TRUE';
      INPUT_LOAD='(-0.01,0.01)';
      OUTPUT_LOAD='(1.0,-1.0)';
    'F6':
      PIN_NUMBER='(F6,0)';
      BIDIRECTIONAL='TRUE';
      INPUT_LOAD='(-0.01,0.01)';
      OUTPUT_LOAD='(1.0,-1.0)';
    'F5':
      PIN_NUMBER='(F5,0)';
      BIDIRECTIONAL='TRUE';
      INPUT_LOAD='(-0.01,0.01)';
      OUTPUT_LOAD='(1.0,-1.0)';
    'G8':
      PIN_NUMBER='(G8,0)';
      BIDIRECTIONAL='TRUE';
      INPUT_LOAD='(-0.01,0.01)';
      OUTPUT_LOAD='(1.0,-1.0)';
    'G7':
      PIN_NUMBER='(G7,0)';
      BIDIRECTIONAL='TRUE';
      INPUT_LOAD='(-0.01,0.01)';
      OUTPUT_LOAD='(1.0,-1.0)';
    'G6':
      PIN_NUMBER='(G6,0)';
      BIDIRECTIONAL='TRUE';
      INPUT_LOAD='(-0.01,0.01)';
      OUTPUT_LOAD='(1.0,-1.0)';
    'G5':
      PIN_NUMBER='(G5,0)';
      BIDIRECTIONAL='TRUE';
      INPUT_LOAD='(-0.01,0.01)';
      OUTPUT_LOAD='(1.0,-1.0)';
    'H8':
      PIN_NUMBER='(H8,0)';
      BIDIRECTIONAL='TRUE';
      INPUT_LOAD='(-0.01,0.01)';
      OUTPUT_LOAD='(1.0,-1.0)';
    'H7':
      PIN_NUMBER='(H7,0)';
      BIDIRECTIONAL='TRUE';
      INPUT_LOAD='(-0.01,0.01)';
      OUTPUT_LOAD='(1.0,-1.0)';
    'H6':
      PIN_NUMBER='(H6,0)';
      BIDIRECTIONAL='TRUE';
      INPUT_LOAD='(-0.01,0.01)';
      OUTPUT_LOAD='(1.0,-1.0)';
    'H5':
      PIN_NUMBER='(H5,0)';
      BIDIRECTIONAL='TRUE';
      INPUT_LOAD='(-0.01,0.01)';
      OUTPUT_LOAD='(1.0,-1.0)';
    'I8':
      PIN_NUMBER='(I8,0)';
      BIDIRECTIONAL='TRUE';
      INPUT_LOAD='(-0.01,0.01)';
      OUTPUT_LOAD='(1.0,-1.0)';
    'I7':
      PIN_NUMBER='(I7,0)';
      BIDIRECTIONAL='TRUE';
      INPUT_LOAD='(-0.01,0.01)';
      OUTPUT_LOAD='(1.0,-1.0)';
    'I6':
      PIN_NUMBER='(I6,0)';
      BIDIRECTIONAL='TRUE';
      INPUT_LOAD='(-0.01,0.01)';
      OUTPUT_LOAD='(1.0,-1.0)';
    'I5':
      PIN_NUMBER='(I5,0)';
      BIDIRECTIONAL='TRUE';
      INPUT_LOAD='(-0.01,0.01)';
      OUTPUT_LOAD='(1.0,-1.0)';
    'J8':
      PIN_NUMBER='(J8,0)';
      BIDIRECTIONAL='TRUE';
      INPUT_LOAD='(-0.01,0.01)';
      OUTPUT_LOAD='(1.0,-1.0)';
    'J7':
      PIN_NUMBER='(J7,0)';
      BIDIRECTIONAL='TRUE';
      INPUT_LOAD='(-0.01,0.01)';
      OUTPUT_LOAD='(1.0,-1.0)';
    'J6':
      PIN_NUMBER='(J6,0)';
      BIDIRECTIONAL='TRUE';
      INPUT_LOAD='(-0.01,0.01)';
      OUTPUT_LOAD='(1.0,-1.0)';
    'J5':
      PIN_NUMBER='(J5,0)';
      BIDIRECTIONAL='TRUE';
      INPUT_LOAD='(-0.01,0.01)';
      OUTPUT_LOAD='(1.0,-1.0)';
    'K8':
      PIN_NUMBER='(K8,0)';
      BIDIRECTIONAL='TRUE';
      INPUT_LOAD='(-0.01,0.01)';
      OUTPUT_LOAD='(1.0,-1.0)';
    'K7':
      PIN_NUMBER='(K7,0)';
      BIDIRECTIONAL='TRUE';
      INPUT_LOAD='(-0.01,0.01)';
      OUTPUT_LOAD='(1.0,-1.0)';
    'K6':
      PIN_NUMBER='(K6,0)';
      BIDIRECTIONAL='TRUE';
      INPUT_LOAD='(-0.01,0.01)';
      OUTPUT_LOAD='(1.0,-1.0)';
    'K5':
      PIN_NUMBER='(K5,0)';
      BIDIRECTIONAL='TRUE';
      INPUT_LOAD='(-0.01,0.01)';
      OUTPUT_LOAD='(1.0,-1.0)';
    'L8':
      PIN_NUMBER='(L8,0)';
      BIDIRECTIONAL='TRUE';
      INPUT_LOAD='(-0.01,0.01)';
      OUTPUT_LOAD='(1.0,-1.0)';
    'L7':
      PIN_NUMBER='(L7,0)';
      BIDIRECTIONAL='TRUE';
      INPUT_LOAD='(-0.01,0.01)';
      OUTPUT_LOAD='(1.0,-1.0)';
    'L6':
      PIN_NUMBER='(L6,0)';
      BIDIRECTIONAL='TRUE';
      INPUT_LOAD='(-0.01,0.01)';
      OUTPUT_LOAD='(1.0,-1.0)';
    'L5':
      PIN_NUMBER='(L5,0)';
      BIDIRECTIONAL='TRUE';
      INPUT_LOAD='(-0.01,0.01)';
      OUTPUT_LOAD='(1.0,-1.0)';
    'M5':
      PIN_NUMBER='(M5,0)';
      BIDIRECTIONAL='TRUE';
      INPUT_LOAD='(-0.01,0.01)';
      OUTPUT_LOAD='(1.0,-1.0)';
    'N5':
      PIN_NUMBER='(N5,0)';
      BIDIRECTIONAL='TRUE';
      INPUT_LOAD='(-0.01,0.01)';
      OUTPUT_LOAD='(1.0,-1.0)';
    'M6':
      PIN_NUMBER='(M6,0)';
      BIDIRECTIONAL='TRUE';
      INPUT_LOAD='(-0.01,0.01)';
      OUTPUT_LOAD='(1.0,-1.0)';
    'N6':
      PIN_NUMBER='(N6,0)';
      BIDIRECTIONAL='TRUE';
      INPUT_LOAD='(-0.01,0.01)';
      OUTPUT_LOAD='(1.0,-1.0)';
    'M7':
      PIN_NUMBER='(M7,0)';
      BIDIRECTIONAL='TRUE';
      INPUT_LOAD='(-0.01,0.01)';
      OUTPUT_LOAD='(1.0,-1.0)';
    'N7':
      PIN_NUMBER='(N7,0)';
      BIDIRECTIONAL='TRUE';
      INPUT_LOAD='(-0.01,0.01)';
      OUTPUT_LOAD='(1.0,-1.0)';
    'M8':
      PIN_NUMBER='(M8,0)';
      BIDIRECTIONAL='TRUE';
      INPUT_LOAD='(-0.01,0.01)';
      OUTPUT_LOAD='(1.0,-1.0)';
    'N8':
      PIN_NUMBER='(N8,0)';
      BIDIRECTIONAL='TRUE';
      INPUT_LOAD='(-0.01,0.01)';
      OUTPUT_LOAD='(1.0,-1.0)';
    'A4':
      PIN_NUMBER='(0,A4)';
      BIDIRECTIONAL='TRUE';
      INPUT_LOAD='(-0.01,0.01)';
      OUTPUT_LOAD='(1.0,-1.0)';
    'A3':
      PIN_NUMBER='(0,A3)';
      BIDIRECTIONAL='TRUE';
      INPUT_LOAD='(-0.01,0.01)';
      OUTPUT_LOAD='(1.0,-1.0)';
    'A2':
      PIN_NUMBER='(0,A2)';
      BIDIRECTIONAL='TRUE';
      INPUT_LOAD='(-0.01,0.01)';
      OUTPUT_LOAD='(1.0,-1.0)';
    'A1':
      PIN_NUMBER='(0,A1)';
      BIDIRECTIONAL='TRUE';
      INPUT_LOAD='(-0.01,0.01)';
      OUTPUT_LOAD='(1.0,-1.0)';
    'B4':
      PIN_NUMBER='(0,B4)';
      BIDIRECTIONAL='TRUE';
      INPUT_LOAD='(-0.01,0.01)';
      OUTPUT_LOAD='(1.0,-1.0)';
    'B3':
      PIN_NUMBER='(0,B3)';
      BIDIRECTIONAL='TRUE';
      INPUT_LOAD='(-0.01,0.01)';
      OUTPUT_LOAD='(1.0,-1.0)';
    'B2':
      PIN_NUMBER='(0,B2)';
      BIDIRECTIONAL='TRUE';
      INPUT_LOAD='(-0.01,0.01)';
      OUTPUT_LOAD='(1.0,-1.0)';
    'B1':
      PIN_NUMBER='(0,B1)';
      BIDIRECTIONAL='TRUE';
      INPUT_LOAD='(-0.01,0.01)';
      OUTPUT_LOAD='(1.0,-1.0)';
    'C4':
      PIN_NUMBER='(0,C4)';
      BIDIRECTIONAL='TRUE';
      INPUT_LOAD='(-0.01,0.01)';
      OUTPUT_LOAD='(1.0,-1.0)';
    'C3':
      PIN_NUMBER='(0,C3)';
      BIDIRECTIONAL='TRUE';
      INPUT_LOAD='(-0.01,0.01)';
      OUTPUT_LOAD='(1.0,-1.0)';
    'C2':
      PIN_NUMBER='(0,C2)';
      BIDIRECTIONAL='TRUE';
      INPUT_LOAD='(-0.01,0.01)';
      OUTPUT_LOAD='(1.0,-1.0)';
    'C1':
      PIN_NUMBER='(0,C1)';
      BIDIRECTIONAL='TRUE';
      INPUT_LOAD='(-0.01,0.01)';
      OUTPUT_LOAD='(1.0,-1.0)';
    'D4':
      PIN_NUMBER='(0,D4)';
      BIDIRECTIONAL='TRUE';
      INPUT_LOAD='(-0.01,0.01)';
      OUTPUT_LOAD='(1.0,-1.0)';
    'D3':
      PIN_NUMBER='(0,D3)';
      BIDIRECTIONAL='TRUE';
      INPUT_LOAD='(-0.01,0.01)';
      OUTPUT_LOAD='(1.0,-1.0)';
    'D2':
      PIN_NUMBER='(0,D2)';
      BIDIRECTIONAL='TRUE';
      INPUT_LOAD='(-0.01,0.01)';
      OUTPUT_LOAD='(1.0,-1.0)';
    'D1':
      PIN_NUMBER='(0,D1)';
      BIDIRECTIONAL='TRUE';
      INPUT_LOAD='(-0.01,0.01)';
      OUTPUT_LOAD='(1.0,-1.0)';
    'E4':
      PIN_NUMBER='(0,E4)';
      BIDIRECTIONAL='TRUE';
      INPUT_LOAD='(-0.01,0.01)';
      OUTPUT_LOAD='(1.0,-1.0)';
    'E3':
      PIN_NUMBER='(0,E3)';
      BIDIRECTIONAL='TRUE';
      INPUT_LOAD='(-0.01,0.01)';
      OUTPUT_LOAD='(1.0,-1.0)';
    'E2':
      PIN_NUMBER='(0,E2)';
      BIDIRECTIONAL='TRUE';
      INPUT_LOAD='(-0.01,0.01)';
      OUTPUT_LOAD='(1.0,-1.0)';
    'E1':
      PIN_NUMBER='(0,E1)';
      BIDIRECTIONAL='TRUE';
      INPUT_LOAD='(-0.01,0.01)';
      OUTPUT_LOAD='(1.0,-1.0)';
    'F4':
      PIN_NUMBER='(0,F4)';
      BIDIRECTIONAL='TRUE';
      INPUT_LOAD='(-0.01,0.01)';
      OUTPUT_LOAD='(1.0,-1.0)';
    'F3':
      PIN_NUMBER='(0,F3)';
      BIDIRECTIONAL='TRUE';
      INPUT_LOAD='(-0.01,0.01)';
      OUTPUT_LOAD='(1.0,-1.0)';
    'F2':
      PIN_NUMBER='(0,F2)';
      BIDIRECTIONAL='TRUE';
      INPUT_LOAD='(-0.01,0.01)';
      OUTPUT_LOAD='(1.0,-1.0)';
    'F1':
      PIN_NUMBER='(0,F1)';
      BIDIRECTIONAL='TRUE';
      INPUT_LOAD='(-0.01,0.01)';
      OUTPUT_LOAD='(1.0,-1.0)';
    'G4':
      PIN_NUMBER='(0,G4)';
      BIDIRECTIONAL='TRUE';
      INPUT_LOAD='(-0.01,0.01)';
      OUTPUT_LOAD='(1.0,-1.0)';
    'G3':
      PIN_NUMBER='(0,G3)';
      BIDIRECTIONAL='TRUE';
      INPUT_LOAD='(-0.01,0.01)';
      OUTPUT_LOAD='(1.0,-1.0)';
    'G2':
      PIN_NUMBER='(0,G2)';
      BIDIRECTIONAL='TRUE';
      INPUT_LOAD='(-0.01,0.01)';
      OUTPUT_LOAD='(1.0,-1.0)';
    'G1':
      PIN_NUMBER='(0,G1)';
      BIDIRECTIONAL='TRUE';
      INPUT_LOAD='(-0.01,0.01)';
      OUTPUT_LOAD='(1.0,-1.0)';
    'H4':
      PIN_NUMBER='(0,H4)';
      BIDIRECTIONAL='TRUE';
      INPUT_LOAD='(-0.01,0.01)';
      OUTPUT_LOAD='(1.0,-1.0)';
    'H3':
      PIN_NUMBER='(0,H3)';
      BIDIRECTIONAL='TRUE';
      INPUT_LOAD='(-0.01,0.01)';
      OUTPUT_LOAD='(1.0,-1.0)';
    'H2':
      PIN_NUMBER='(0,H2)';
      BIDIRECTIONAL='TRUE';
      INPUT_LOAD='(-0.01,0.01)';
      OUTPUT_LOAD='(1.0,-1.0)';
    'H1':
      PIN_NUMBER='(0,H1)';
      BIDIRECTIONAL='TRUE';
      INPUT_LOAD='(-0.01,0.01)';
      OUTPUT_LOAD='(1.0,-1.0)';
    'I4':
      PIN_NUMBER='(0,I4)';
      BIDIRECTIONAL='TRUE';
      INPUT_LOAD='(-0.01,0.01)';
      OUTPUT_LOAD='(1.0,-1.0)';
    'I3':
      PIN_NUMBER='(0,I3)';
      BIDIRECTIONAL='TRUE';
      INPUT_LOAD='(-0.01,0.01)';
      OUTPUT_LOAD='(1.0,-1.0)';
    'I2':
      PIN_NUMBER='(0,I2)';
      BIDIRECTIONAL='TRUE';
      INPUT_LOAD='(-0.01,0.01)';
      OUTPUT_LOAD='(1.0,-1.0)';
    'I1':
      PIN_NUMBER='(0,I1)';
      BIDIRECTIONAL='TRUE';
      INPUT_LOAD='(-0.01,0.01)';
      OUTPUT_LOAD='(1.0,-1.0)';
    'J4':
      PIN_NUMBER='(0,J4)';
      BIDIRECTIONAL='TRUE';
      INPUT_LOAD='(-0.01,0.01)';
      OUTPUT_LOAD='(1.0,-1.0)';
    'J3':
      PIN_NUMBER='(0,J3)';
      BIDIRECTIONAL='TRUE';
      INPUT_LOAD='(-0.01,0.01)';
      OUTPUT_LOAD='(1.0,-1.0)';
    'J2':
      PIN_NUMBER='(0,J2)';
      BIDIRECTIONAL='TRUE';
      INPUT_LOAD='(-0.01,0.01)';
      OUTPUT_LOAD='(1.0,-1.0)';
    'J1':
      PIN_NUMBER='(0,J1)';
      BIDIRECTIONAL='TRUE';
      INPUT_LOAD='(-0.01,0.01)';
      OUTPUT_LOAD='(1.0,-1.0)';
    'K4':
      PIN_NUMBER='(0,K4)';
      BIDIRECTIONAL='TRUE';
      INPUT_LOAD='(-0.01,0.01)';
      OUTPUT_LOAD='(1.0,-1.0)';
    'K3':
      PIN_NUMBER='(0,K3)';
      BIDIRECTIONAL='TRUE';
      INPUT_LOAD='(-0.01,0.01)';
      OUTPUT_LOAD='(1.0,-1.0)';
    'K2':
      PIN_NUMBER='(0,K2)';
      BIDIRECTIONAL='TRUE';
      INPUT_LOAD='(-0.01,0.01)';
      OUTPUT_LOAD='(1.0,-1.0)';
    'K1':
      PIN_NUMBER='(0,K1)';
      BIDIRECTIONAL='TRUE';
      INPUT_LOAD='(-0.01,0.01)';
      OUTPUT_LOAD='(1.0,-1.0)';
    'L4':
      PIN_NUMBER='(0,L4)';
      BIDIRECTIONAL='TRUE';
      INPUT_LOAD='(-0.01,0.01)';
      OUTPUT_LOAD='(1.0,-1.0)';
    'L3':
      PIN_NUMBER='(0,L3)';
      BIDIRECTIONAL='TRUE';
      INPUT_LOAD='(-0.01,0.01)';
      OUTPUT_LOAD='(1.0,-1.0)';
    'L2':
      PIN_NUMBER='(0,L2)';
      BIDIRECTIONAL='TRUE';
      INPUT_LOAD='(-0.01,0.01)';
      OUTPUT_LOAD='(1.0,-1.0)';
    'L1':
      PIN_NUMBER='(0,L1)';
      BIDIRECTIONAL='TRUE';
      INPUT_LOAD='(-0.01,0.01)';
      OUTPUT_LOAD='(1.0,-1.0)';
    'M1':
      PIN_NUMBER='(0,M1)';
      BIDIRECTIONAL='TRUE';
      INPUT_LOAD='(-0.01,0.01)';
      OUTPUT_LOAD='(1.0,-1.0)';
    'N1':
      PIN_NUMBER='(0,N1)';
      BIDIRECTIONAL='TRUE';
      INPUT_LOAD='(-0.01,0.01)';
      OUTPUT_LOAD='(1.0,-1.0)';
    'M2':
      PIN_NUMBER='(0,M2)';
      BIDIRECTIONAL='TRUE';
      INPUT_LOAD='(-0.01,0.01)';
      OUTPUT_LOAD='(1.0,-1.0)';
    'N2':
      PIN_NUMBER='(0,N2)';
      BIDIRECTIONAL='TRUE';
      INPUT_LOAD='(-0.01,0.01)';
      OUTPUT_LOAD='(1.0,-1.0)';
    'M3':
      PIN_NUMBER='(0,M3)';
      BIDIRECTIONAL='TRUE';
      INPUT_LOAD='(-0.01,0.01)';
      OUTPUT_LOAD='(1.0,-1.0)';
    'N3':
      PIN_NUMBER='(0,N3)';
      BIDIRECTIONAL='TRUE';
      INPUT_LOAD='(-0.01,0.01)';
      OUTPUT_LOAD='(1.0,-1.0)';
    'M4':
      PIN_NUMBER='(0,M4)';
      BIDIRECTIONAL='TRUE';
      INPUT_LOAD='(-0.01,0.01)';
      OUTPUT_LOAD='(1.0,-1.0)';
    'N4':
      PIN_NUMBER='(0,N4)';
      BIDIRECTIONAL='TRUE';
      INPUT_LOAD='(-0.01,0.01)';
      OUTPUT_LOAD='(1.0,-1.0)';
  end_pin;
  body
    PART_NAME='CONN112_10137002101LF';
    BODY_NAME='CONN112_10137002101LF';
    PHYS_DES_PREFIX='J';
    CLASS='IO';
  end_body;
end_primitive;

END.
